FILE_TYPE = CONNECTIVITY;
{Allegro Design Entry HDL 16.6-p007 (v16-6-112F) 10/10/2012}
"PAGE_NUMBER" = 202;
0"NC";
1"GND\g";
2"PVCCIN_CPU0\g";
3"GND\g";
4"GND\g";
5"PVCCIN_CPU0\g";
6"VR_FET_SW_P12V_STBY_PVCCIN_CPU0\g";
7"GND\g";
8"VR_FET_SW_P12V_STBY_PVCCIN_CPU0\g";
9"GND\g";
10"P5V_STBY\g";
11"P5V_STBY\g";
12"GND\g";
13"GND\g";
14"GND\g";
15"GND\g";
16"GND\g";
17"GND\g";
18"GND\g";
19"GND\g";
20"GND\g";
21"VR_PVCCIN_CPU0_PH1_PHASE"VOLTAGE"5";
22"VR_PVCCIN_CPU0_PH1_BOOT";
23"VR_PVCCIN_CPU0_AIREF2";
24"VR_PVCCIN_CPU0_PH1_OCSET";
25"A_TSENSE_PVCCIN_CPU0";
26"VR_PVCCIN_CPU0_PH2_PHASE"VOLTAGE"5";
27"VR_PVCCIN_CPU0_PH2_BOOT_R";
28"VR_PVCCIN_CPU0_PWM2";
29"VR_PVCCIN_CPU0_PH2_OCSET"VOLTAGE"3.6";
30"VR_PVCCIN_CPU0_PH2_VCIN"VOLTAGE"5";
31"VR_PVCCIN_CPU0_PWM1";
32"ISENSE_PVCCIN_CPU0_PH2_IMON";
33"A_TSENSE_PVCCIN_CPU0";
34"VR_PVCCIN_CPU0_PHASE2"VOLTAGE"5";
35"NC_PVCCIN_CPU0_PH2_P31";
36"TP_PVCCIN_CPU0_PH2_GL_0";
37"TP_PVCCIN_CPU0_PH2_GL_1";
38"VR_PVCCIN_CPU0_PH2_BOOT";
39"NC_PVCCIN_CPU0_PH1_P31";
40"VR_PVCCIN_CPU0_PHASE1"VOLTAGE"5";
41"UN$202$3D01R5F-GP$I75$2";
42"TP_PVCCIN_CPU0_PH1_GL_0";
43"TP_PVCCIN_CPU0_PH1_GL_1";
44"VR_PVCCIN_CPU0_PH1_BOOT_R";
45"VR_PVCCIN_CPU0_PH1_VCIN"VOLTAGE"5";
46"VR_PVCCIN_CPU0_AIREF1";
47"ISENSE_PVCCIN_CPU0_PH1_IMON";
48"UN$202$3D01R5F-GP$I83$2";
%"GND"
"1","(-2800,3125)","0","mstr_symbols","I13";
;
CDS_LIB"mstr_symbols"
ROOM"PVCCIN_CPU0_PWR_VR"
BOM_COST"PROC_VRD_VCCIN_CPU0"
BODY_TYPE"PLUMBING"
VOLTAGE"0"
SIZE"1B"
HDL_POWER"GND";
"A\NAC"1;
%"CAP"
"1","(-5025,4125)","0","mstr_discrete","I18";
;
CDS_SEC"1"
CDS_LIB"mstr_discrete"
SEC_TYPE"0402"
SEC"1"
CDS_LOCATION"C4E5"
ROOM"PVCCIN_CPU0_PWR_VR"
PART_NUMBER"A36096-155"
MATERIAL"X7R"
TOLERANCE"10%"
LOCATION"C4E5"
PACK_TYPE"0402"
VALUE"0.22UF"
VOLTAGE"16V";
"A"
$PN"1"11;
"B"
$PN"2"7;
%"CAP_A"
"1","(-5125,4125)","2","dev_discrete","I19";
;
CDS_LOCATION"C4E6"
CDS_LIB"dev_discrete"
CDS_SEC"1"
SEC_TYPE"0402V"
SEC"1"
ROOM"PVCCIN_CPU0_PWR_VR"
PART_NUMBER"D97712-004"
TOLERANCE"10%"
VOLTAGE"6.3V"
LOCATION"C4E6"
PACK_TYPE"0402V"
MATERIAL"X6S"
VALUE"1.0UF";
"B"
$PN"2"7;
"A"
$PN"1"11;
%"CAP"
"1","(-5850,3450)","2","mstr_discrete","I22";
;
CDS_SEC"1"
CDS_LOCATION"C4E17"
CDS_LIB"mstr_discrete"
SEC_TYPE"0402"
SPOF"TRUE"
SEC"1"
NO_XNET_CONNECTION"1"
ROOM"PVCCIN_CPU0_PWR_VR"
PART_NUMBER"A36096-104"
VALUE"0.220UF"
VOLTAGE"16V"
LOCATION"C4E17"
TOLERANCE"10%"
MATERIAL"X7R"
PACK_TYPE"0402";
"A"
$PN"1"22;
"B"
$PN"2"21;
%"CAP"
"1","(-5100,1425)","0","mstr_discrete","I24";
;
CDS_SEC"1"
CDS_LOCATION"C4E27"
CDS_LIB"mstr_discrete"
SEC_TYPE"0402"
SEC"1"
ROOM"PVCCIN_CPU0_PWR_VR"
VOLTAGE"16V"
PART_NUMBER"A36096-155"
TOLERANCE"10%"
VALUE"0.22UF"
MATERIAL"X7R"
LOCATION"C4E27"
PACK_TYPE"0402";
"A"
$PN"1"10;
"B"
$PN"2"9;
%"CAP_A"
"1","(-5225,1450)","2","dev_discrete","I25";
;
CDS_LOCATION"C4E25"
CDS_LIB"dev_discrete"
SEC"1"
SEC_TYPE"0402V"
ROOM"PVCCIN_CPU0_PWR_VR"
CDS_SEC"1"
VALUE"1.0UF"
VOLTAGE"6.3V"
MATERIAL"X6S"
TOLERANCE"10%"
LOCATION"C4E25"
PACK_TYPE"0402V"
PART_NUMBER"D97712-004";
"B"
$PN"2"9;
"A"
$PN"1"10;
%"PVCCIN_CPU0"
"1","(-575,1000)","0","mstr_symbols","I26";
;
HDL_POWER"PVCCIN_CPU0"
CDS_LIB"mstr_symbols"
BODY_TYPE"PLUMBING"
VOLTAGE"2.0V";
"G\NAC"2;
%"CAP_A"
"1","(-875,650)","0","dev_discrete","I27";
;
SEC"1"
SEC_TYPE"0603V"
CDS_LOCATION"C4E11"
BOM_COST"PROC_VRD_VCCIN_CPU0"
CDS_SEC"1"
ROOM"PVCCIN_CPU0_PWR_VR"
CDS_LIB"dev_discrete"
LOCATION"C4E11"
PACK_TYPE"0603V"
TOLERANCE"20%"
VOLTAGE"4V"
PART_NUMBER"E15431-004"
VALUE"22.0UF"
MATERIAL"X6S";
"B"
$PN"2"3;
"A"
$PN"1"2;
%"GND"
"1","(-575,350)","0","mstr_symbols","I28";
;
ROOM"PVCCIN_CPU0_PWR_VR"
BOM_COST"PROC_VRD_VCCIN_CPU0"
BODY_TYPE"PLUMBING"
SIZE"1B"
CDS_LIB"mstr_symbols"
VOLTAGE"0"
HDL_POWER"GND";
"A\NAC"3;
%"INDUCTOR"
"1","(-1700,925)","0","mstr_discrete","I29";
;
CDS_SEC"1"
$SEC"1"
ROOM"PVCCIN_CPU0_PWR_VR"
CDS_LIB"mstr_discrete"
CDS_LOCATION"L4D3"
PART_NUMBER"D92183-034"
PACK_TYPE"SM"
VALUE"0.12UH"
LOCATION"L4D3"
MATERIAL"IND";
"INA\NAC"
$PN"1"34;
"INB\NAC"
$PN"2"2;
%"GND"
"1","(-2800,525)","0","mstr_symbols","I30";
;
ROOM"PVCCIN_CPU0_PWR_VR"
BOM_COST"PROC_VRD_VCCIN_CPU0"
BODY_TYPE"PLUMBING"
SIZE"1B"
VOLTAGE"0"
CDS_LIB"mstr_symbols"
HDL_POWER"GND";
"A\NAC"4;
%"CAP"
"1","(-5950,825)","2","mstr_discrete","I32";
;
CDS_SEC"1"
CDS_LOCATION"C4D50"
NO_XNET_CONNECTION"1"
SEC"1"
SPOF"TRUE"
SEC_TYPE"0402"
ROOM"PVCCIN_CPU0_PWR_VR"
CDS_LIB"mstr_discrete"
LOCATION"C4D50"
VALUE"0.220UF"
TOLERANCE"10%"
PACK_TYPE"0402"
VOLTAGE"16V"
MATERIAL"X7R"
PART_NUMBER"A36096-104";
"A"
$PN"1"38;
"B"
$PN"2"26;
%"RES"
"1","(-5500,4625)","0","mstr_discrete","I33";
;
CDS_SEC"1"
SEC"1"
CDS_LOCATION"R6R2"
ROOM"PVCCIN_CPU0_PWR_VR"
CDS_LIB"mstr_discrete"
SEC_TYPE"0402"
PACK_TYPE"0402"
VALUE"1.0"
TOLERANCE"1%"
WATTAGE"1/16W"
MATERIAL"CHIP"
PART_NUMBER"G21796-090"
LOCATION"R6R2";
"B"
$PN"2"11;
"A"
$PN"1"45;
%"CAP"
"1","(-5750,4025)","0","mstr_discrete","I34";
;
CDS_SEC"1"
CDS_LIB"mstr_discrete"
SEC_TYPE"0402"
SEC"1"
CDS_LOCATION"C4E10"
ROOM"PVCCIN_CPU0_PWR_VR"
PART_NUMBER"D97712-011"
MATERIAL"X6S"
VOLTAGE"16V"
PACK_TYPE"0402"
TOLERANCE"10%"
VALUE"1.0UF"
LOCATION"C4E10";
"A"
$PN"1"45;
"B"
$PN"2"7;
%"CAP_A"
"1","(-6050,4025)","0","dev_discrete","I35";
;
CDS_LOCATION"C4E20"
CDS_SEC"1"
CDS_LIB"dev_discrete"
SEC_TYPE"0402V"
SEC"1"
ROOM"PVCCIN_CPU0_PWR_VR"
PART_NUMBER"A36096-030"
VALUE"0.1UF"
PACK_TYPE"0402V"
MATERIAL"X7R"
VOLTAGE"16V"
TOLERANCE"10%"
LOCATION"C4E20";
"B"
$PN"2"7;
"A"
$PN"1"6;
%"CAP"
"1","(-6325,4050)","0","mstr_discrete","I36";
;
CDS_SEC"1"
CDS_LIB"mstr_discrete"
ROOM"PVCCIN_CPU0_PWR_VR"
CDS_LOCATION"C4E19"
SEC"1"
SEC_TYPE"0402"
TOLERANCE"10%"
PACK_TYPE"0402"
VOLTAGE"16V"
MATERIAL"X6S"
PART_NUMBER"D97712-011"
VALUE"1.0UF"
LOCATION"C4E19";
"A"
$PN"1"6;
"B"
$PN"2"7;
%"CAP"
"1","(-6600,4050)","0","mstr_discrete","I37";
;
CDS_SEC"1"
CDS_LIB"mstr_discrete"
ROOM"PVCCIN_CPU0_PWR_VR"
CDS_LOCATION"C6R11"
SEC"1"
SEC_TYPE"0805"
LOCATION"C6R11"
VALUE"10UF"
VOLTAGE"16V"
TOLERANCE"10%"
MATERIAL"X6S"
PART_NUMBER"C95333-007"
PACK_TYPE"0805";
"A"
$PN"1"6;
"B"
$PN"2"7;
%"CAP"
"1","(-6900,4075)","0","mstr_discrete","I38";
;
CDS_SEC"1"
CDS_LIB"mstr_discrete"
SEC_TYPE"0805"
CDS_LOCATION"C6P13"
SEC"1"
ROOM"PVCCIN_CPU0_PWR_VR"
TOLERANCE"10%"
VOLTAGE"16V"
VALUE"10UF"
LOCATION"C6P13"
PACK_TYPE"0805"
PART_NUMBER"C95333-007"
MATERIAL"X6S";
"A"
$PN"1"6;
"B"
$PN"2"7;
%"RES"
"1","(-5625,1975)","0","mstr_discrete","I39";
;
CDS_SEC"1"
CDS_LOCATION"R6R6"
CDS_LIB"mstr_discrete"
ROOM"PVCCIN_CPU0_PWR_VR"
SEC"1"
SEC_TYPE"0402"
TOLERANCE"1%"
VALUE"1.0"
PART_NUMBER"G21796-090"
PACK_TYPE"0402"
MATERIAL"CHIP"
LOCATION"R6R6"
WATTAGE"1/16W";
"B"
$PN"2"10;
"A"
$PN"1"30;
%"PVCCIN_CPU0"
"1","(-1075,3675)","0","mstr_symbols","I4";
;
VOLTAGE"2.0V"
BOM_COST"PROC_SOCKET "
CDS_LIB"mstr_symbols"
BODY_TYPE"PLUMBING"
ROOM"PVCCIN_CPU0_PWR_VR"
HDL_POWER"PVCCIN_CPU0";
"G\NAC"5;
%"VCC_CORE"
"1","(-7200,4525)","0","mstr_symbols","I41";
;
CDS_LIB"mstr_symbols"
HDL_POWER"VR_FET_SW_P12V_STBY_PVCCIN_CPU0";
"A"6;
%"CAP"
"1","(-7200,4075)","0","mstr_discrete","I42";
;
CDS_SEC"1"
CDS_LIB"mstr_discrete"
ROOM"PVCCIN_CPU0_PWR_VR"
CDS_LOCATION"C6R13"
SEC"1"
SEC_TYPE"0805"
VALUE"10UF"
PART_NUMBER"C95333-007"
MATERIAL"X6S"
PACK_TYPE"0805"
TOLERANCE"10%"
VOLTAGE"16V"
LOCATION"C6R13";
"A"
$PN"1"6;
"B"
$PN"2"7;
%"GND"
"1","(-7200,3525)","0","mstr_symbols","I43";
;
ROOM"PVCCIN_CPU0_PWR_VR"
BODY_TYPE"PLUMBING"
VOLTAGE"0"
CDS_LIB"mstr_symbols"
BOM_COST"PROC_VRD_VCCIN_CPU0"
HDL_POWER"GND"
SIZE"1B";
"A\NAC"7;
%"VCC_CORE"
"1","(-7225,1900)","0","mstr_symbols","I44";
;
CDS_LIB"mstr_symbols"
HDL_POWER"VR_FET_SW_P12V_STBY_PVCCIN_CPU0";
"A"8;
%"CAP"
"1","(-5950,1425)","0","mstr_discrete","I45";
;
CDS_SEC"1"
CDS_LOCATION"C4E26"
CDS_LIB"mstr_discrete"
SEC_TYPE"0402"
SEC"1"
ROOM"PVCCIN_CPU0_PWR_VR"
VALUE"1.0UF"
TOLERANCE"10%"
VOLTAGE"16V"
MATERIAL"X6S"
LOCATION"C4E26"
PART_NUMBER"D97712-011"
PACK_TYPE"0402";
"A"
$PN"1"30;
"B"
$PN"2"9;
%"CAP_A"
"1","(-6225,1475)","0","dev_discrete","I46";
;
CDS_LOCATION"C4D49"
CDS_LIB"dev_discrete"
ROOM"PVCCIN_CPU0_PWR_VR"
CDS_SEC"1"
SEC_TYPE"0402V"
SEC"1"
MATERIAL"X7R"
VOLTAGE"16V"
PACK_TYPE"0402V"
TOLERANCE"10%"
VALUE"0.1UF"
PART_NUMBER"A36096-030"
LOCATION"C4D49";
"B"
$PN"2"9;
"A"
$PN"1"8;
%"CAP"
"1","(-6450,1425)","0","mstr_discrete","I47";
;
CDS_SEC"1"
CDS_LOCATION"C4D48"
CDS_LIB"mstr_discrete"
SEC_TYPE"0402"
SEC"1"
ROOM"PVCCIN_CPU0_PWR_VR"
MATERIAL"X6S"
VOLTAGE"16V"
PACK_TYPE"0402"
VALUE"1.0UF"
TOLERANCE"10%"
LOCATION"C4D48"
PART_NUMBER"D97712-011";
"A"
$PN"1"8;
"B"
$PN"2"9;
%"CAP"
"1","(-6725,1425)","0","mstr_discrete","I48";
;
CDS_SEC"1"
CDS_LIB"mstr_discrete"
CDS_LOCATION"C6R4"
SEC_TYPE"0805"
SEC"1"
ROOM"PVCCIN_CPU0_PWR_VR"
MATERIAL"X6S"
VOLTAGE"16V"
PACK_TYPE"0805"
TOLERANCE"10%"
VALUE"10UF"
PART_NUMBER"C95333-007"
LOCATION"C6R4";
"A"
$PN"1"8;
"B"
$PN"2"9;
%"CAP"
"1","(-6975,1450)","0","mstr_discrete","I49";
;
CDS_SEC"1"
CDS_LIB"mstr_discrete"
SEC_TYPE"0805"
SEC"1"
CDS_LOCATION"C6P22"
ROOM"PVCCIN_CPU0_PWR_VR"
MATERIAL"X6S"
VOLTAGE"16V"
PACK_TYPE"0805"
TOLERANCE"10%"
VALUE"10UF"
PART_NUMBER"C95333-007"
LOCATION"C6P22";
"A"
$PN"1"8;
"B"
$PN"2"9;
%"INDUCTOR"
"1","(-1775,3500)","0","mstr_discrete","I5";
;
CDS_LOCATION"L4E1"
CDS_LIB"mstr_discrete"
ROOM"PVCCIN_CPU0_PWR_VR"
$SEC"1"
CDS_SEC"1"
PACK_TYPE"SM"
MATERIAL"IND"
LOCATION"L4E1"
PART_NUMBER"D92183-034"
VALUE"0.12UH";
"INA\NAC"
$PN"1"40;
"INB\NAC"
$PN"2"5;
%"CAP"
"1","(-7225,1475)","0","mstr_discrete","I51";
;
CDS_SEC"1"
CDS_LIB"mstr_discrete"
CDS_LOCATION"C6N8"
ROOM"PVCCIN_CPU0_PWR_VR"
SEC"1"
SEC_TYPE"0805"
MATERIAL"X6S"
VOLTAGE"16V"
PACK_TYPE"0805"
TOLERANCE"10%"
VALUE"10UF"
PART_NUMBER"C95333-007"
LOCATION"C6N8";
"A"
$PN"1"8;
"B"
$PN"2"9;
%"GND"
"1","(-7225,1050)","0","mstr_symbols","I52";
;
BODY_TYPE"PLUMBING"
ROOM"PVCCIN_CPU0_PWR_VR"
BOM_COST"PROC_VRD_VCCIN_CPU0"
CDS_LIB"mstr_symbols"
VOLTAGE"0"
HDL_POWER"GND"
SIZE"1B";
"A\NAC"9;
%"P5V_STBY"
"1","(-4700,2100)","0","mstr_symbols","I59";
;
HDL_POWER"P5V_STBY"
BODY_TYPE"PLUMBING"
SIZE"1B"
CDS_LIB"mstr_symbols"
VOLTAGE"5.0V";
"G\NAC"10;
%"P5V_STBY"
"1","(-4675,4750)","0","mstr_symbols","I60";
;
HDL_POWER"P5V_STBY"
BODY_TYPE"PLUMBING"
VOLTAGE"5.0V"
CDS_LIB"mstr_symbols"
SIZE"1B";
"G\NAC"11;
%"CAP_A"
"1","(-875,3300)","0","dev_discrete","I61";
;
CDS_LIB"dev_discrete"
SEC_TYPE"0603V"
SEC"1"
CDS_LOCATION"C4E3"
CDS_SEC"1"
VOLTAGE"4V"
LOCATION"C4E3"
PART_NUMBER"E15431-004"
VALUE"22.0UF"
PACK_TYPE"0603V"
TOLERANCE"20%"
MATERIAL"X6S";
"B"
$PN"2"17;
"A"
$PN"1"5;
%"CAP_A"
"1","(-575,650)","0","dev_discrete","I62";
;
SEC_TYPE"0603V"
CDS_SEC"1"
CDS_LOCATION"C6P16"
SEC"1"
CDS_LIB"dev_discrete"
PART_NUMBER"E15431-004"
LOCATION"C6P16"
TOLERANCE"20%"
MATERIAL"X6S"
PACK_TYPE"0603V"
VALUE"22.0UF"
VOLTAGE"4V";
"B"
$PN"2"3;
"A"
$PN"1"2;
%"IR354XX"
"1","(-3425,3800)","0","mstr_discrete","I63";
;
$SEC"1"
CDS_SEC"1"
PACK_TYPE"SM"
CDS_LOCATION"EU4E1"
CDS_LIB"mstr_discrete"
PART_NUMBER"H73688-001"
VALUE"IR35411"
LOCATION"EU4E1"
MATERIAL"IC";
"TOUT_FLT"
$PN"36"25;
"NC"
$PN"31"39;
"OCSET"
$PN"37"24;
"IOUT"
$PN"38"47;
"SW"
$PN"10"40;
"BOOST"
$PN"33"44;
"REFIN"
$PN"39"46;
"PWM"
$PN"34"31;
"PHASE"
$PN"32"21;
"VIN<0>"
$PN"25"6;
"VCC"
$PN"3"45;
"VIN<1>"
$PN"30"6;
"EN"
$PN"35"11;
"VDRV"
$PN"4"11;
"VOS"
$PN"1"5;
"LGND"
$PN"2"1;
"PGND<1>"
$PN"7"1;
"PGND<2>"
$PN"40"1;
"PGND<0>"
$PN"5"1;
"GL<0>"
$PN"6"42;
"GL<1>"
$PN"41"43;
%"IR354XX"
"1","(-3475,1175)","0","mstr_discrete","I64";
;
PACK_TYPE"SM"
CDS_SEC"1"
$SEC"1"
CDS_LIB"mstr_discrete"
CDS_LOCATION"EU4D6"
PART_NUMBER"H73688-001"
MATERIAL"IC"
LOCATION"EU4D6"
VALUE"IR35411";
"TOUT_FLT"
$PN"36"33;
"NC"
$PN"31"35;
"OCSET"
$PN"37"29;
"IOUT"
$PN"38"32;
"SW"
$PN"10"34;
"BOOST"
$PN"33"27;
"REFIN"
$PN"39"23;
"PWM"
$PN"34"28;
"PHASE"
$PN"32"26;
"VIN<0>"
$PN"25"8;
"VCC"
$PN"3"30;
"VIN<1>"
$PN"30"8;
"EN"
$PN"35"10;
"VDRV"
$PN"4"10;
"VOS"
$PN"1"2;
"LGND"
$PN"2"4;
"PGND<1>"
$PN"7"4;
"PGND<2>"
$PN"40"4;
"PGND<0>"
$PN"5"4;
"GL<0>"
$PN"6"36;
"GL<1>"
$PN"41"37;
%"RES"
"2","(-750,3900)","0","mstr_discrete","I65";
;
CDS_LOCATION"R4E22"
CDS_LIB"mstr_discrete"
$SEC"1"
CDS_SEC"1"
PACK_TYPE"0402"
MATERIAL"EMPTY"
TOLERANCE"1%"
WATTAGE"1/16W"
VALUE"68.1K"
LOCATION"R4E22"
PART_NUMBER"G21796-187";
"A"
$PN"1"24;
"B"
$PN"2"12;
%"GND"
"1","(-750,3700)","0","mstr_symbols","I66";
;
ROOM"PVCCIN_CPU0_PWR_VR"
BOM_COST"PROC_VRD_VCCIN_CPU0"
BODY_TYPE"PLUMBING"
SIZE"1B"
CDS_LIB"mstr_symbols"
VOLTAGE"0"
HDL_POWER"GND";
"A\NAC"12;
%"RES"
"2","(-825,1350)","0","mstr_discrete","I67";
;
CDS_LOCATION"R4E19"
CDS_LIB"mstr_discrete"
$SEC"1"
CDS_SEC"1"
WATTAGE"1/16W"
PART_NUMBER"G21796-187"
PACK_TYPE"0402"
VALUE"68.1K"
TOLERANCE"1%"
MATERIAL"EMPTY"
LOCATION"R4E19";
"A"
$PN"1"29;
"B"
$PN"2"13;
%"GND"
"1","(-825,1150)","0","mstr_symbols","I68";
;
ROOM"PVCCIN_CPU0_PWR_VR"
BOM_COST"PROC_VRD_VCCIN_CPU0"
BODY_TYPE"PLUMBING"
CDS_LIB"mstr_symbols"
VOLTAGE"0"
HDL_POWER"GND"
SIZE"1B";
"A\NAC"13;
%"CAP_A"
"1","(-4125,3300)","0","dev_discrete","I70";
;
CDS_SEC"1"
$SEC"1"
CDS_LOCATION"CT1"
CDS_LIB"dev_discrete"
ROOM"PVCCIN_CPU0_PWR_VR"
LOCATION"CT1"
STATUS"NOPOP"
VALUE"0.1UF"
TOLERANCE"10%"
MATERIAL"X7R"
PART_NUMBER"A36096-030"
PACK_TYPE"0402V"
VOLTAGE"16V";
"B"
$PN"2"14;
"A"
$PN"1"46;
%"GND"
"1","(-4125,3050)","0","mstr_symbols","I71";
;
CDS_LIB"mstr_symbols"
HDL_POWER"GND"
VOLTAGE"0"
SIZE"1B"
BOM_COST"PROC_VRD_VCCIN_CPU0"
ROOM"PVCCIN_CPU0_PWR_VR"
BODY_TYPE"PLUMBING";
"A\NAC"14;
%"GND"
"1","(-2350,3625)","0","mstr_symbols","I73";
;
CDS_LIB"mstr_symbols"
ROOM"VDDQ_KLM_PWR_VR"
VOLTAGE"0"
BODY_TYPE"PLUMBING"
SIZE"1B"
HDL_POWER"GND";
"A\NAC"15;
%"3D01R5F-GP"
"1","(-2550,3050)","4","w_hdl","I75";
;
CDS_SEC"1"
$SEC"1"
CDS_LOCATION"RT2"
PACK_TYPE"SMD-RG5"
PART_NUMBER"64.3R015.16L"
CDS_LIB"w_hdl"
CDS_LMAN_SYM_OUTLINE"-50,75,50,-75"
LOCATION"RT2"
VALUE"3D01R5F-GP"
STATUS"NOPOP";
"2"
$PN"2"41;
"1"
$PN"1"16;
%"SC2K2P50V3KX-GP"
"1","(-2550,3350)","0","w_hdl","I76";
;
CDS_SEC"1"
$SEC"1"
CDS_LOCATION"CT3"
CDS_LIB"w_hdl"
CDS_LMAN_SYM_OUTLINE"-50,25,50,-25"
PACK_TYPE"SMD-BCG6"
PART_NUMBER"78.22224.2BL"
VALUE"SC2K2P50V3KX-GP"
LOCATION"CT3"
STATUS"NOPOP";
"2"
$PN"2"41;
"1"
$PN"1"40;
%"GND"
"1","(-2550,2800)","0","mstr_symbols","I77";
;
CDS_LIB"mstr_symbols"
ROOM"PVCCIN_CPU0_PWR_VR"
BOM_COST"PROC_VRD_VCCIN_CPU0"
BODY_TYPE"PLUMBING"
VOLTAGE"0"
SIZE"1B"
HDL_POWER"GND";
"A\NAC"16;
%"CAP"
"1","(-2350,3875)","0","mstr_discrete","I78";
;
CDS_SEC"1"
CDS_LOCATION"CT2"
CDS_LIB"mstr_discrete"
SEC_TYPE"0402LF"
SEC"1"
ROOM"VDDQ_KLM_PWR_VR"
VALUE"1000PF"
LOCATION"CT2"
PACK_TYPE"0402LF"
TOLERANCE"10%"
STATUS"NOPOP"
VOLTAGE"50V"
MATERIAL"X7R"
PART_NUMBER"A36096-046";
"A"
$PN"1"25;
"B"
$PN"2"15;
%"GND"
"1","(-1000,3000)","0","mstr_symbols","I8";
;
CDS_LIB"mstr_symbols"
HDL_POWER"GND"
VOLTAGE"0"
SIZE"1B"
BOM_COST"PROC_VRD_VCCIN_CPU0"
ROOM"PVCCIN_CPU0_PWR_VR"
BODY_TYPE"PLUMBING";
"A\NAC"17;
%"GND"
"1","(-4175,425)","0","mstr_symbols","I80";
;
CDS_LIB"mstr_symbols"
HDL_POWER"GND"
VOLTAGE"0"
SIZE"1B"
BOM_COST"PROC_VRD_VCCIN_CPU0"
ROOM"PVCCIN_CPU0_PWR_VR"
BODY_TYPE"PLUMBING";
"A\NAC"18;
%"CAP_A"
"1","(-4175,675)","0","dev_discrete","I81";
;
CDS_SEC"1"
$SEC"1"
CDS_LOCATION"CT6"
CDS_LIB"dev_discrete"
ROOM"PVCCIN_CPU0_PWR_VR"
PART_NUMBER"A36096-030"
PACK_TYPE"0402V"
TOLERANCE"10%"
VOLTAGE"16V"
LOCATION"CT6"
VALUE"0.1UF"
MATERIAL"X7R"
STATUS"NOPOP";
"B"
$PN"2"18;
"A"
$PN"1"23;
%"SC2K2P50V3KX-GP"
"1","(-2450,800)","0","w_hdl","I82";
;
CDS_SEC"1"
$SEC"1"
CDS_LOCATION"CT5"
CDS_LIB"w_hdl"
CDS_LMAN_SYM_OUTLINE"-50,25,50,-25"
PART_NUMBER"78.22224.2BL"
PACK_TYPE"SMD-BCG6"
VALUE"SC2K2P50V3KX-GP"
LOCATION"CT5"
STATUS"NOPOP";
"2"
$PN"2"48;
"1"
$PN"1"34;
%"3D01R5F-GP"
"1","(-2450,575)","4","w_hdl","I83";
;
CDS_SEC"1"
$SEC"1"
CDS_LOCATION"RT4"
PACK_TYPE"SMD-RG5"
PART_NUMBER"64.3R015.16L"
CDS_LIB"w_hdl"
CDS_LMAN_SYM_OUTLINE"-50,75,50,-75"
STATUS"NOPOP"
VALUE"3D01R5F-GP"
LOCATION"RT4";
"2"
$PN"2"48;
"1"
$PN"1"19;
%"GND"
"1","(-2450,375)","0","mstr_symbols","I84";
;
ROOM"PVCCIN_CPU0_PWR_VR"
BOM_COST"PROC_VRD_VCCIN_CPU0"
BODY_TYPE"PLUMBING"
VOLTAGE"0"
SIZE"1B"
HDL_POWER"GND"
CDS_LIB"mstr_symbols";
"A\NAC"19;
%"GND"
"1","(-2450,1050)","0","mstr_symbols","I86";
;
CDS_LIB"mstr_symbols"
ROOM"VDDQ_KLM_PWR_VR"
VOLTAGE"0"
BODY_TYPE"PLUMBING"
SIZE"1B"
HDL_POWER"GND";
"A\NAC"20;
%"CAP"
"1","(-2450,1250)","0","mstr_discrete","I87";
;
CDS_LOCATION"CT4"
CDS_SEC"1"
$SEC"1"
ROOM"VDDQ_KLM_PWR_VR"
CDS_LIB"mstr_discrete"
MATERIAL"X7R"
PACK_TYPE"0402LF"
TOLERANCE"10%"
VOLTAGE"50V"
VALUE"1000PF"
LOCATION"CT4"
PART_NUMBER"A36096-046"
STATUS"NOPOP";
"A"
$PN"1"33;
"B"
$PN"2"20;
%"RES"
"1","(-4925,3575)","0","mstr_discrete","I88";
;
CDS_SEC"1"
$SEC"1"
CDS_LOCATION"RT1"
CDS_LIB"mstr_discrete"
BOM_COST"DEBUG"
ROOM"BMC_DEBUG_HEADER"
TOLERANCE"5%"
VALUE"0.0"
WATTAGE"1/16W"
LOCATION"RT1"
PART_NUMBER"G21497-005"
MATERIAL"CHIP"
PACK_TYPE"0402";
"B"
$PN"2"44;
"A"
$PN"1"22;
%"RES"
"1","(-4975,950)","0","mstr_discrete","I89";
;
CDS_SEC"1"
$SEC"1"
CDS_LOCATION"RT3"
BOM_COST"DEBUG"
ROOM"BMC_DEBUG_HEADER"
CDS_LIB"mstr_discrete"
LOCATION"RT3"
WATTAGE"1/16W"
VALUE"0.0"
MATERIAL"CHIP"
TOLERANCE"5%"
PACK_TYPE"0402"
PART_NUMBER"G21497-005";
"B"
$PN"2"27;
"A"
$PN"1"38;
%"CAP_A"
"1","(-1250,3300)","0","dev_discrete","I9";
;
CDS_LIB"dev_discrete"
CDS_LOCATION"C6R7"
ROOM"PVCCIN_CPU0_PWR_VR"
CDS_SEC"1"
BOM_COST"PROC_VRD_VCCIN_CPU0"
SEC"1"
SEC_TYPE"0603V"
PART_NUMBER"E15431-004"
MATERIAL"X6S"
VOLTAGE"4V"
PACK_TYPE"0603V"
TOLERANCE"20%"
VALUE"22.0UF"
LOCATION"C6R7";
"B"
$PN"2"17;
"A"
$PN"1"5;
END.
